# T6G (Grand Teton) — schematic netlist excerpt (pin names and nets, part order shuffled) for the footprints in the layout excerpt that follows; sources: Cadence DE-HDL packaged netlist, KiCad conversion of 04192023_DAF0TMB3IC0_F0TG_MB_C_brd_V02_OCP.brd

R2932  Q_RES  4.7K 5% CHIP  pkg 0402LF  page 128 : A = FM_SWB_PWR_EN_R1_BUF ; B = GND
R3198  Q_RES  0 5% CHIP  pkg 0402LF  page 55 : A = CLK_100M_CPU1_CLK04_R_DP ; B = CLK_100M_CPU1_CLK04_DP

(kicad_pcb
	(version 20260206)
	(generator "pcbnew")
	(generator_version "10.0")
	(general
		(thickness 1.6)
		(legacy_teardrops no)
	)
	(paper "A4")
	(title_block
		(title "04192023_DAF0TMB3IC0_F0TG_MB_C_brd_V02_OCP.brd")
		(comment 1 "Grand Teton / footprints 1750-1751 of 8354")
	)
	(layers
		(0 "F.Cu" signal "TOP")
		(4 "In1.Cu" signal "GND")
		(6 "In2.Cu" signal "IN1")
		(8 "In3.Cu" signal "GND1")
		(10 "In4.Cu" signal "IN2")
		(12 "In5.Cu" signal "GND2")
		(14 "In6.Cu" signal "IN3")
		(16 "In7.Cu" signal "GND3")
		(18 "In8.Cu" signal "VCC")
		(20 "In9.Cu" signal "VCC1")
		(22 "In10.Cu" signal "GND4")
		(24 "In11.Cu" signal "IN4")
		(26 "In12.Cu" signal "GND5")
		(28 "In13.Cu" signal "IN5")
		(30 "In14.Cu" signal "GND6")
		(32 "In15.Cu" signal "IN6")
		(34 "In16.Cu" signal "GND7")
		(2 "B.Cu" signal "BOTTOM")
		(9 "F.Adhes" user "F.Adhesive")
		(11 "B.Adhes" user "B.Adhesive")
		(13 "F.Paste" user "Package Geometry/Pastemask Top")
		(15 "B.Paste" user "Package Geometry/Pastemask Bottom")
		(5 "F.SilkS" user "Ref Des/Silkscreen Top")
		(7 "B.SilkS" user "Ref Des/Silkscreen Bottom")
		(1 "F.Mask" user "Board Geometry/Soldermask Top")
		(3 "B.Mask" user "Board Geometry/Soldermask Bottom")
		(17 "Dwgs.User" user "User.Drawings")
		(19 "Cmts.User" user "User.Comments")
		(21 "Eco1.User" user "User.Eco1")
		(23 "Eco2.User" user "User.Eco2")
		(25 "Edge.Cuts" user "Board Geometry/Outline")
		(27 "Margin" user)
		(31 "F.CrtYd" user "Package Geometry/Place Bound Top")
		(29 "B.CrtYd" user "Package Geometry/Place Bound Bottom")
		(35 "F.Fab" user "Ref Des/Assembly Top")
		(33 "B.Fab" user "Ref Des/Assembly Bottom")
	)
	(footprint ""
		(layer "F.Cu")
		(at 147.09775 -191.35471 -90)
		(property "Reference" "R3198"
			(at 0 0 270)
			(layer "F.SilkS")
			(hide yes)
			(effects
				(font
					(size 1.27 1.27)
				)
			)
		)
		(property "Value" ""
			(at 0 0 270)
			(layer "F.Fab")
			(effects
				(font
					(size 1.27 1.27)
				)
			)
		)
		(duplicate_pad_numbers_are_jumpers no)
		(fp_line
			(start -0.7874 0.4064)
			(end -0.7874 -0.01905)
			(stroke
				(width 0.1524)
				(type default)
			)
			(layer "F.SilkS")
		)
		(fp_line
			(start 0.7874 0.4064)
			(end -0.7874 0.4064)
			(stroke
				(width 0.1524)
				(type default)
			)
			(layer "F.SilkS")
		)
		(fp_line
			(start 0.7874 -0.04445)
			(end 0.7874 0.4064)
			(stroke
				(width 0.1524)
				(type default)
			)
			(layer "F.SilkS")
		)
		(fp_line
			(start -0.33909 -0.4064)
			(end 0.42291 -0.4064)
			(stroke
				(width 0.1524)
				(type default)
			)
			(layer "F.SilkS")
		)
		(fp_line
			(start -0.67945 0.3048)
			(end -0.67945 -0.305054)
			(stroke
				(width 0.1)
				(type default)
			)
			(layer "F.Fab")
		)
		(fp_line
			(start -0.12065 0.3048)
			(end -0.67945 0.3048)
			(stroke
				(width 0.1)
				(type default)
			)
			(layer "F.Fab")
		)
		(fp_line
			(start 0.120396 0.3048)
			(end 0.120396 0.2794)
			(stroke
				(width 0.1)
				(type default)
			)
			(layer "F.Fab")
		)
		(fp_line
			(start 0.67945 0.3048)
			(end 0.120396 0.3048)
			(stroke
				(width 0.1)
				(type default)
			)
			(layer "F.Fab")
		)
		(fp_line
			(start -0.12065 0.2794)
			(end -0.12065 0.3048)
			(stroke
				(width 0.1)
				(type default)
			)
			(layer "F.Fab")
		)
		(fp_line
			(start 0.120396 0.2794)
			(end -0.12065 0.2794)
			(stroke
				(width 0.1)
				(type default)
			)
			(layer "F.Fab")
		)
		(fp_line
			(start -0.12065 -0.2794)
			(end 0.12065 -0.2794)
			(stroke
				(width 0.1)
				(type default)
			)
			(layer "F.Fab")
		)
		(fp_line
			(start 0.12065 -0.2794)
			(end 0.12065 -0.3048)
			(stroke
				(width 0.1)
				(type default)
			)
			(layer "F.Fab")
		)
		(fp_line
			(start 0.12065 -0.3048)
			(end 0.67945 -0.3048)
			(stroke
				(width 0.1)
				(type default)
			)
			(layer "F.Fab")
		)
		(fp_line
			(start 0.67945 -0.3048)
			(end 0.67945 0.3048)
			(stroke
				(width 0.1)
				(type default)
			)
			(layer "F.Fab")
		)
		(fp_line
			(start -0.67945 -0.305054)
			(end -0.12065 -0.305054)
			(stroke
				(width 0.1)
				(type default)
			)
			(layer "F.Fab")
		)
		(fp_line
			(start -0.12065 -0.305054)
			(end -0.12065 -0.2794)
			(stroke
				(width 0.1)
				(type default)
			)
			(layer "F.Fab")
		)
		(pad "1" smd circle
			(at -0.40005 0 270)
			(size 0 0)
			(layers "F.Cu" "F.Mask" "F.Paste")
			(net "CLK_100M_CPU1_CLK04_R_DP")
		)
		(pad "2" smd circle
			(at 0.40005 0 270)
			(size 0 0)
			(layers "F.Cu" "F.Mask" "F.Paste")
			(net "CLK_100M_CPU1_CLK04_DP")
		)
	)
	(footprint ""
		(layer "F.Cu")
		(at 39.30396 -434.086 -90)
		(property "Reference" "R2932"
			(at 0 0 270)
			(layer "F.SilkS")
			(hide yes)
			(effects
				(font
					(size 1.27 1.27)
				)
			)
		)
		(property "Value" ""
			(at 0 0 270)
			(layer "F.Fab")
			(effects
				(font
					(size 1.27 1.27)
				)
			)
		)
		(duplicate_pad_numbers_are_jumpers no)
		(fp_line
			(start -0.7874 0.4064)
			(end -0.7874 -0.4064)
			(stroke
				(width 0.1524)
				(type default)
			)
			(layer "F.SilkS")
		)
		(fp_line
			(start 0.7874 0.4064)
			(end -0.7874 0.4064)
			(stroke
				(width 0.1524)
				(type default)
			)
			(layer "F.SilkS")
		)
		(fp_line
			(start -0.7874 -0.4064)
			(end 0.7874 -0.4064)
			(stroke
				(width 0.1524)
				(type default)
			)
			(layer "F.SilkS")
		)
		(fp_line
			(start 0.7874 -0.4064)
			(end 0.7874 0.4064)
			(stroke
				(width 0.1524)
				(type default)
			)
			(layer "F.SilkS")
		)
		(fp_line
			(start -0.67945 0.3048)
			(end -0.67945 -0.305054)
			(stroke
				(width 0.1)
				(type default)
			)
			(layer "F.Fab")
		)
		(fp_line
			(start -0.12065 0.3048)
			(end -0.67945 0.3048)
			(stroke
				(width 0.1)
				(type default)
			)
			(layer "F.Fab")
		)
		(fp_line
			(start 0.120396 0.3048)
			(end 0.120396 0.2794)
			(stroke
				(width 0.1)
				(type default)
			)
			(layer "F.Fab")
		)
		(fp_line
			(start 0.67945 0.3048)
			(end 0.120396 0.3048)
			(stroke
				(width 0.1)
				(type default)
			)
			(layer "F.Fab")
		)
		(fp_line
			(start -0.12065 0.2794)
			(end -0.12065 0.3048)
			(stroke
				(width 0.1)
				(type default)
			)
			(layer "F.Fab")
		)
		(fp_line
			(start 0.120396 0.2794)
			(end -0.12065 0.2794)
			(stroke
				(width 0.1)
				(type default)
			)
			(layer "F.Fab")
		)
		(fp_line
			(start -0.12065 -0.2794)
			(end 0.12065 -0.2794)
			(stroke
				(width 0.1)
				(type default)
			)
			(layer "F.Fab")
		)
		(fp_line
			(start 0.12065 -0.2794)
			(end 0.12065 -0.3048)
			(stroke
				(width 0.1)
				(type default)
			)
			(layer "F.Fab")
		)
		(fp_line
			(start 0.12065 -0.3048)
			(end 0.67945 -0.3048)
			(stroke
				(width 0.1)
				(type default)
			)
			(layer "F.Fab")
		)
		(fp_line
			(start 0.67945 -0.3048)
			(end 0.67945 0.3048)
			(stroke
				(width 0.1)
				(type default)
			)
			(layer "F.Fab")
		)
		(fp_line
			(start -0.67945 -0.305054)
			(end -0.12065 -0.305054)
			(stroke
				(width 0.1)
				(type default)
			)
			(layer "F.Fab")
		)
		(fp_line
			(start -0.12065 -0.305054)
			(end -0.12065 -0.2794)
			(stroke
				(width 0.1)
				(type default)
			)
			(layer "F.Fab")
		)
		(pad "1" smd circle
			(at -0.40005 0 270)
			(size 0 0)
			(layers "F.Cu" "F.Mask" "F.Paste")
			(net "FM_SWB_PWR_EN_R1_BUF")
		)
		(pad "2" smd circle
			(at 0.40005 0 270)
			(size 0 0)
			(layers "F.Cu" "F.Mask" "F.Paste")
			(net "GND")
		)
	)
)
